FILE_TYPE = CONNECTIVITY;
{Allegro Design Entry HDL 17.2-2016 S081 (4005846) 1/11/2022}
"PAGE_NUMBER" = 278;
0"NC";
1"PVCCINFAON_CPU1\g";
2"PVNN_TERM_CPU1\g";
3"P12V_AUX\g";
4"P3V3_AUX\g";
5"P3V3_AUX\g";
6"PVCCFA_EHV_CPU1\g";
7"P3V3_AUX\g";
8"P3V3_AUX\g";
9"P3V3_AUX\g";
10"GND\g";
11"GND\g";
12"GND\g";
13"GND\g";
14"GND\g";
15"GND\g";
16"GND\g";
17"GND\g";
18"GND\g";
19"GND\g";
20"GND\g";
21"GND\g";
22"GND\g";
23"GND\g";
24"GND\g";
25"GND\g";
26"GND\g";
27"GND\g";
28"GND\g";
29"GND\g";
30"GND\g";
31"SH_PVCCFA_EHV_CPU1_R";
32"VSENSE_PVCCFA_EHV_CPU1_DN";
33"PVCCFA_EHV_CPU1_EN_R";
34"SMB_CLK_PVCCINFAON_CPU1";
35"SVID_DIO_PVCCINFAON_CPU1_R";
36"SVID_ALERT_PVCCINFAON_CPU1_R";
37"PWRGD_PVCCFA_EHV_CPU1_R";
38"SVID_CLK_PVCCINFAON_CPU1_R";
39"NC_PVCCINFAON_CPU1_SMB_ALERT";
40"PVCCINFAON_CPU1_EN_R";
41"VSENSE_PVCCINFAON_CPU1_DN";
42"SMB_DIO_PVCCINFAON_CPU1";
43"SH_PVCCINFAON_CPU1_R";
44"PWRGD_PVCCINFAON_CPU1_R";
45"PVCCINFAON_CPU1_CSPIN";
46"PVCCINFAON_CPU1_VIN_CSNIN";
47"PVCCINFAON_CPU1_PIN_ALERT";
48"PVCCINFAON_CPU1_VR_FAULT";
49"PVCCINFAON_CPU1_ADDR";
50"PVCCFA_EHV_CPU1_BCSP1";
51"PVCCFA_EHV_CPU1_BPWM1";
52"PVCCINFAON_CPU1_ATSEN";
53"NC_PVCCINFAON_CPU1_ACSP6";
54"NC_PVCCINFAON_CPU1_APWM6";
55"NC_PVCCINFAON_CPU1_ACSP5";
56"NC_PVCCINFAON_CPU1_APWM5";
57"PVCCINFAON_CPU1_APWM1";
58"NC_PVCCINFAON_CPU1_ACSP7";
59"PVCCFA_EHV_CPU1_BTSEN";
60"PVCCINFAON_CPU1_VREF";
61"PVCCINFAON_CPU1_APWM2";
62"NC_PVCCINFAON_CPU1_APWM7";
63"NC_PVCCINFAON_CPU1_APWM3";
64"NC_PVCCINFAON_CPU1_APWM4";
65"NC_PVCCINFAON_CPU1_ACSP4";
66"NC_PVCCINFAON_CPU1_ACSP3";
67"IRQ_PVCCFA_CPU1_VRHOT_N";
68"PVCCINFAON_CPU1_ACSP2";
69"PVCCINFAON_CPU1_VCC";
70"PVCCINFAON_CPU1_ACSP1";
71"IRQ_PVCCFA_CPU1_VRHOT_R_N";
72"PWRGD_PVCCFA_EHV_CPU1";
73"PVCCINFAON_CPU1_VREF";
74"SH_PVCCINFAON_CPU1";
75"VSENSE_PVCCINFAON_CPU1_DP";
76"SH_PVCCFA_EHV_CPU1";
77"VSENSE_PVCCFA_EHV_CPU1_DP";
78"FM_PVCCFA_EHV_CPU1_EN";
79"SVID_ALERT0_CPU1_R_N";
80"PWRGD_PVCCINFAON_CPU1";
81"SVID_DIO0_CPU1_R";
82"SMB_VR_3V3AUX_SDA_R";
83"SVID_CLK0_CPU1_R";
84"FM_PVCCINFAON_CPU1_EN";
85"SMB_VR_3V3AUX_SCL_R";
%"UNIVERSAL_GND"
"1","(5650,8750)","3","logical_power","I100";
;
HDL_POWER"GND"
CDS_LIB"logical_power";
"A"29;
%"VCC15"
"1","(750,9400)","0","logical_power","I102";
;
HDL_POWER"P3V3_AUX"
CDS_LIB"logical_power";
"A"8;
%"Q_RES"
"1","(1175,9150)","0","pure_quanta","I103";
;
PART_NUMBER"CS00002JB13"
TOLERANCE"5%"
MATERIAL"CHIP"
VALUE"0"
PACK_TYPE"0402LF"
WATTAGE"1/16W"
LOCATION"R4781"
CDS_LIB"pure_quanta"
LOCATION"R4781"
$SEC"1"
CDS_SEC"1";
"B"
$PN"2"44;
"A"
$PN"1"80;
%"Q_RES"
"1","(1175,9000)","0","pure_quanta","I104";
;
PART_NUMBER"CS00002JB13"
WATTAGE"1/16W"
PACK_TYPE"0402LF"
TOLERANCE"5%"
MATERIAL"CHIP"
VALUE"0"
LOCATION"R2558"
CDS_LIB"pure_quanta"
SEC_TYPE"0402LF"
SEC"1";
"B"
$PN"2"40;
"A"
$PN"1"84;
%"Q_RES"
"1","(1175,9300)","0","pure_quanta","I105";
;
PART_NUMBER"CS21002FB06"
MATERIAL"CHIP"
WATTAGE"1/16W"
TOLERANCE"1%"
VALUE"1K"
PACK_TYPE"0402LF"
LOCATION"R2556"
CDS_LIB"pure_quanta"
LOCATION"R2556"
$SEC"1"
CDS_SEC"1";
"B"
$PN"2"44;
"A"
$PN"1"8;
%"Q_CAP"
"2","(2025,9300)","0","pure_quanta","I106";
;
PART_NUMBER"TMP_QCH21006JB10"
TOLERANCE"5%"
MATERIAL"EMPTY"
VALUE"1000PF"
VOLTAGE"50V"
PACK_TYPE"0402"
LOCATION"C2450"
CDS_LIB"pure_quanta"
LOCATION"C2450"
$SEC"1"
CDS_SEC"1";
"A"
$PN"1"44;
"B"
$PN"2"30;
%"UNIVERSAL_GND"
"1","(2725,9300)","1","logical_power","I107";
;
HDL_POWER"GND"
CDS_LIB"logical_power";
"A"30;
%"Q_RES"
"1","(5525,9150)","0","pure_quanta","I108";
;
PART_NUMBER"CS-1002FB04"
PACK_TYPE"0402LF"
VALUE"1"
MATERIAL"CHIP"
TOLERANCE"1%"
WATTAGE"1/16W"
LOCATION"PR283"
CDS_LIB"pure_quanta"
LOCATION"PR283"
$SEC"1"
CDS_SEC"1";
"B"
$PN"2"9;
"A"
$PN"1"69;
%"VCC15"
"1","(6000,9275)","0","logical_power","I109";
;
HDL_POWER"P3V3_AUX"
CDS_LIB"logical_power";
"A"9;
%"Q_RES"
"2","(625,3825)","0","pure_quanta","I110";
;
PART_NUMBER"CS28452FB06"
PACK_TYPE"0402LF"
TOLERANCE"1%"
VALUE"8.45K"
WATTAGE"1/16W"
MATERIAL"CHIP"
LOCATION"PR259"
CDS_LIB"pure_quanta"
$SEC"1"
CDS_SEC"1";
"A"
$PN"1"49;
"B"
$PN"2"10;
%"Q_CAP"
"1","(4450,8950)","0","pure_quanta","I111";
;
PART_NUMBER"CH4104K1B00"
TOLERANCE"10%"
PACK_TYPE"0402"
MATERIAL"EMPTY"
VOLTAGE"25V"
VALUE"0.1UF"
LOCATION"PC2367"
CDS_LIB"pure_quanta"
$SEC"1"
CDS_SEC"1";
"B"
$PN"2"29;
"A"
$PN"1"69;
%"Q_RES"
"1","(-100,8800)","0","pure_quanta","I14";
;
PART_NUMBER"CS11002FB07"
MATERIAL"EMPTY"
PACK_TYPE"0402LF"
WATTAGE"1/16W"
VALUE"100"
TOLERANCE"1%"
LOCATION"R2354"
CDS_LIB"pure_quanta"
$SEC"1"
CDS_SEC"1";
"B"
$PN"2"81;
"A"
$PN"1"2;
%"Q_RES"
"1","(-100,8900)","0","pure_quanta","I15";
;
PART_NUMBER"CS04992FB07"
WATTAGE"1/16W"
MATERIAL"EMPTY"
PACK_TYPE"0402LF"
VALUE"49.9"
TOLERANCE"1%"
LOCATION"R2345"
CDS_LIB"pure_quanta"
$SEC"1"
CDS_SEC"1";
"B"
$PN"2"83;
"A"
$PN"1"2;
%"VCC15"
"1","(-825,9025)","0","logical_power","I16";
;
HDL_POWER"PVNN_TERM_CPU1"
CDS_LIB"logical_power";
"A"2;
%"UNIVERSAL_GND"
"1","(625,3600)","0","logical_power","I19";
;
HDL_POWER"GND"
CDS_LIB"logical_power";
"A"10;
%"Q_RES"
"1","(1100,3700)","0","pure_quanta","I21";
;
PART_NUMBER"CS00002JB13"
PACK_TYPE"0402LF"
TOLERANCE"5%"
VALUE"0"
MATERIAL"CHIP"
WATTAGE"1/16W"
LOCATION"PR261"
CDS_LIB"pure_quanta"
LOCATION"PR261"
$SEC"1"
CDS_SEC"1";
"B"
$PN"2"46;
"A"
$PN"1"3;
%"Q_RES"
"1","(1100,3800)","0","pure_quanta","I22";
;
PART_NUMBER"CS00002JB13"
PACK_TYPE"0402LF"
TOLERANCE"5%"
VALUE"0"
MATERIAL"EMPTY"
LOCATION"PR260"
CDS_LIB"pure_quanta"
WATTAGE"1/16W"
LOCATION"PR260"
$SEC"1"
CDS_SEC"1";
"B"
$PN"2"45;
"A"
$PN"1"3;
%"Q_RES"
"1","(500,4050)","0","pure_quanta","I23";
;
PART_NUMBER"CS32802FB05"
VALUE"28K"
TOLERANCE"1%"
PACK_TYPE"0402LF"
WATTAGE"1/16W"
MATERIAL"EMPTY"
LOCATION"PR258"
CDS_LIB"pure_quanta"
LOCATION"PR258"
$SEC"1"
CDS_SEC"1";
"B"
$PN"2"49;
"A"
$PN"1"73;
%"VCC15"
"1","(825,3925)","0","logical_power","I24";
;
HDL_POWER"P12V_AUX"
CDS_LIB"logical_power";
"A"3;
%"VCC15"
"1","(875,4600)","0","logical_power","I25";
;
HDL_POWER"P3V3_AUX"
CDS_LIB"logical_power";
"A"4;
%"Q_RES"
"2","(1550,3500)","0","pure_quanta","I26";
;
PART_NUMBER"CS00002JB13"
MATERIAL"CHIP"
WATTAGE"1/16W"
TOLERANCE"5%"
PACK_TYPE"0402LF"
VALUE"0"
LOCATION"PR275"
CDS_LIB"pure_quanta"
LOCATION"PR275"
$SEC"1"
CDS_SEC"1";
"A"
$PN"1"45;
"B"
$PN"2"11;
%"UNIVERSAL_GND"
"1","(1875,3200)","0","logical_power","I27";
;
HDL_POWER"GND"
CDS_LIB"logical_power";
"A"11;
%"Q_CAP"
"1","(1875,3500)","0","pure_quanta","I28";
;
PART_NUMBER"CH4104K1B00"
MATERIAL"EMPTY"
TOLERANCE"10%"
VOLTAGE"25V"
PACK_TYPE"0402"
VALUE"0.1UF"
LOCATION"PC467"
CDS_LIB"pure_quanta"
LOCATION"PC467"
$SEC"1"
CDS_SEC"1";
"B"
$PN"2"11;
"A"
$PN"1"45;
%"Q_RES"
"1","(1350,4350)","0","pure_quanta","I29";
;
PART_NUMBER"CS00002JB13"
VALUE"0"
MATERIAL"CHIP"
WATTAGE"1/16W"
PACK_TYPE"0402LF"
TOLERANCE"5%"
LOCATION"R2572"
CDS_LIB"pure_quanta"
LOCATION"R2572"
$SEC"1"
CDS_SEC"1";
"B"
$PN"2"37;
"A"
$PN"1"72;
%"Q_RES"
"1","(1350,4500)","0","pure_quanta","I30";
;
PART_NUMBER"CS21002FB06"
MATERIAL"CHIP"
TOLERANCE"1%"
PACK_TYPE"0402LF"
WATTAGE"1/16W"
VALUE"1K"
LOCATION"R2571"
CDS_LIB"pure_quanta"
LOCATION"R2571"
$SEC"1"
CDS_SEC"1";
"B"
$PN"2"37;
"A"
$PN"1"4;
%"Q_RES"
"1","(1350,4750)","0","pure_quanta","I31";
;
PART_NUMBER"CS00002JB13"
WATTAGE"1/16W"
MATERIAL"CHIP"
PACK_TYPE"0402LF"
TOLERANCE"5%"
VALUE"0"
LOCATION"R2570"
CDS_LIB"pure_quanta"
LOCATION"R2570"
$SEC"1"
CDS_SEC"1";
"B"
$PN"2"33;
"A"
$PN"1"78;
%"Q_CAP"
"2","(2150,4500)","0","pure_quanta","I32";
;
PART_NUMBER"TMP_QCH21006JB10"
PACK_TYPE"0402"
TOLERANCE"5%"
VALUE"1000PF"
MATERIAL"EMPTY"
VOLTAGE"50V"
LOCATION"C2453"
CDS_LIB"pure_quanta"
LOCATION"C2453"
$SEC"1"
CDS_SEC"1";
"A"
$PN"1"37;
"B"
$PN"2"14;
%"Q_CAP"
"2","(2150,4625)","0","pure_quanta","I33";
;
PART_NUMBER"TMP_QCH21006JB10"
MATERIAL"X7R"
VOLTAGE"50V"
VALUE"1000PF"
TOLERANCE"5%"
PACK_TYPE"0402"
LOCATION"C2452"
CDS_LIB"pure_quanta"
LOCATION"C2452"
$SEC"1"
CDS_SEC"1";
"A"
$PN"1"33;
"B"
$PN"2"15;
%"UNIVERSAL_GND"
"1","(2625,3200)","0","logical_power","I34";
;
HDL_POWER"GND"
CDS_LIB"logical_power";
"A"12;
%"Q_RES"
"2","(2300,3500)","0","pure_quanta","I35";
;
PART_NUMBER"CS21002FB06"
WATTAGE"1/16W"
MATERIAL"EMPTY"
TOLERANCE"1%"
VALUE"1K"
PACK_TYPE"0402LF"
LOCATION"PR276"
CDS_LIB"pure_quanta"
LOCATION"PR276"
$SEC"1"
CDS_SEC"1";
"A"
$PN"1"46;
"B"
$PN"2"12;
%"Q_CAP"
"1","(2625,3500)","0","pure_quanta","I36";
;
PART_NUMBER"CH4104K1B00"
VOLTAGE"25V"
TOLERANCE"10%"
VALUE"0.1UF"
PACK_TYPE"0402"
MATERIAL"X7R"
LOCATION"PC474"
CDS_LIB"pure_quanta"
LOCATION"PC474"
$SEC"1"
CDS_SEC"1";
"B"
$PN"2"12;
"A"
$PN"1"46;
%"UNIVERSAL_GND"
"1","(2800,3475)","0","logical_power","I37";
;
HDL_POWER"GND"
CDS_LIB"logical_power";
"A"13;
%"ISL69260IRAZT"
"1","(3550,6400)","0","pure_quanta","I38";
;
PART_NUMBER"AL069260000"
VALUE"ISL69260IRAZ-T"
MATERIAL"IC"
PART_TYPE"SMLF"
LOCATION"PU22"
NEEDS_NO_SIZE"TRUE"
CDS_LMAN_SYM_OUTLINE"-550,2850,500,-2850"
CDS_LIB"pure_quanta"
$SEC"1"
CDS_SEC"1";
"CS0"
$PN"30"50;
"PWM0"
$PN"1"51;
"TEMP0"
$PN"35"52;
"ADDR_CFG"
$PN"34"49;
"TH_GND"
$PN"TH"13;
"CFP"
$PN"33"48;
"CS2"
$PN"28"53;
"PWM2"
$PN"3"54;
"CS3"
$PN"27"55;
"PWM3"
$PN"4"56;
"PWM7"
$PN"8"57;
"CS1"
$PN"29"58;
"RGND1"
$PN"31"32;
"VSEN1"
$PN"32"31;
"NPINALERT#||NPSYSCRIT# \B"
$PN"15"47;
"TEMP1||ISYS"
$PN"36"59;
"VINSEN||VSYS"
$PN"38"46;
"VMON||IINSEN||VSYS||ISYS"
$PN"37"45;
"VCCS"
$PN"40"60;
"PWM6"
$PN"7"61;
"PG0"
$PN"12"44;
"PWM1"
$PN"2"62;
"VSEN0"
$PN"21"43;
"PWM5"
$PN"6"63;
"PWM4"
$PN"5"64;
"PMSDA"
$PN"9"42;
"RGND0"
$PN"22"41;
"EN0"
$PN"13"40;
"NPMALERT# \B"
$PN"11"39;
"SVCLK"
$PN"17"38;
"PG1"
$PN"16"37;
"CS4"
$PN"26"65;
"CS5"
$PN"25"66;
"NVRHOT# \B"
$PN"14"67;
"NSVALERT# \B"
$PN"19"36;
"CS6"
$PN"24"68;
"SVDATA"
$PN"18"35;
"PMSCL"
$PN"10"34;
"EN1"
$PN"20"33;
"VCC"
$PN"39"69;
"CS7"
$PN"23"70;
%"UNIVERSAL_GND"
"1","(2850,4500)","1","logical_power","I39";
;
HDL_POWER"GND"
CDS_LIB"logical_power";
"A"14;
%"UNIVERSAL_GND"
"1","(2850,4625)","1","logical_power","I40";
;
HDL_POWER"GND"
CDS_LIB"logical_power";
"A"15;
%"Q_RES"
"1","(550,5525)","0","pure_quanta","I41";
;
PART_NUMBER"CS11002FB07"
MATERIAL"CHIP"
TOLERANCE"1%"
VALUE"100"
PACK_TYPE"0402LF"
WATTAGE"1/16W"
LOCATION"PR567"
CDS_LIB"pure_quanta"
$SEC"1"
CDS_SEC"1";
"B"
$PN"2"16;
"A"
$PN"1"32;
%"VCC15"
"1","(1025,5275)","0","logical_power","I42";
;
HDL_POWER"P3V3_AUX"
CDS_LIB"logical_power";
"A"5;
%"UNIVERSAL_GND"
"1","(1025,5425)","0","logical_power","I43";
;
HDL_POWER"GND"
CDS_LIB"logical_power";
"A"16;
%"Q_SHORT"
"1","(475,6050)","0","pure_quanta","I44";
;
PART_NUMBER"SHORT6"
PACK_TYPE"SM"
MATERIAL"EMPTY"
LOCATION"PJ51"
NEEDS_NO_SIZE"TRUE"
CDS_LIB"pure_quanta"
LOCATION"PJ51"
$SEC"1"
CDS_SEC"1";
"1"
$PN"1"77;
"2"
$PN"2"76;
%"Q_RES"
"1","(550,6200)","0","pure_quanta","I45";
;
PART_NUMBER"CS11002FB07"
TOLERANCE"1%"
VALUE"100"
PACK_TYPE"0402LF"
WATTAGE"1/16W"
MATERIAL"CHIP"
LOCATION"PR569"
CDS_LIB"pure_quanta"
$SEC"1"
CDS_SEC"1";
"B"
$PN"2"6;
"A"
$PN"1"77;
%"Q_RES"
"1","(550,6625)","0","pure_quanta","I46";
;
PART_NUMBER"CS11002FB07"
VALUE"100"
MATERIAL"CHIP"
PACK_TYPE"0402LF"
TOLERANCE"1%"
WATTAGE"1/16W"
LOCATION"PR566"
CDS_LIB"pure_quanta"
$SEC"1"
CDS_SEC"1";
"B"
$PN"2"17;
"A"
$PN"1"41;
%"VCC15"
"1","(1050,6350)","0","logical_power","I47";
;
HDL_POWER"PVCCFA_EHV_CPU1"
CDS_LIB"logical_power";
"A"6;
%"UNIVERSAL_GND"
"1","(1025,6525)","0","logical_power","I48";
;
HDL_POWER"GND"
CDS_LIB"logical_power";
"A"17;
%"Q_RES"
"1","(1350,5050)","0","pure_quanta","I49";
;
PART_NUMBER"CS21002FB06"
VALUE"1K"
PACK_TYPE"0402LF"
TOLERANCE"1%"
LOCATION"R2569"
CDS_LIB"pure_quanta"
WATTAGE"1/16W"
MATERIAL"CHIP"
$SEC"1"
CDS_SEC"1";
"B"
$PN"2"47;
"A"
$PN"1"5;
%"Q_RES"
"1","(1350,5150)","0","pure_quanta","I50";
;
PART_NUMBER"CS21002FB06"
TOLERANCE"1%"
MATERIAL"CHIP"
VALUE"1K"
PACK_TYPE"0402LF"
WATTAGE"1/16W"
LOCATION"R2568"
CDS_LIB"pure_quanta"
$SEC"1"
CDS_SEC"1";
"B"
$PN"2"48;
"A"
$PN"1"5;
%"Q_CAP"
"1","(1975,5875)","0","pure_quanta","I51";
;
PART_NUMBER"TMP_QCH2336K1B12"
MATERIAL"X7R"
TOLERANCE"10%"
VALUE"3300PF"
VOLTAGE"50V"
PACK_TYPE"0402"
LOCATION"PC469"
CDS_LIB"pure_quanta"
LOCATION"PC469"
$SEC"1"
CDS_SEC"1";
"B"
$PN"2"32;
"A"
$PN"1"31;
%"Q_RES"
"1","(1525,6050)","0","pure_quanta","I52";
;
PART_NUMBER"CS00002JB13"
WATTAGE"1/16W"
MATERIAL"CHIP"
TOLERANCE"5%"
VALUE"0"
PACK_TYPE"0402LF"
LOCATION"PR274"
CDS_LIB"pure_quanta"
LOCATION"PR274"
$SEC"1"
CDS_SEC"1";
"B"
$PN"2"31;
"A"
$PN"1"76;
%"Q_CAP"
"1","(1975,6975)","0","pure_quanta","I53";
;
PART_NUMBER"TMP_QCH2336K1B12"
VALUE"3300PF"
MATERIAL"X7R"
TOLERANCE"10%"
VOLTAGE"50V"
PACK_TYPE"0402"
LOCATION"PC468"
CDS_LIB"pure_quanta"
LOCATION"PC468"
$SEC"1"
CDS_SEC"1";
"B"
$PN"2"41;
"A"
$PN"1"43;
%"Q_SHORT"
"1","(475,7150)","0","pure_quanta","I54";
;
PART_NUMBER"SHORT6"
MATERIAL"EMPTY"
PACK_TYPE"SM"
LOCATION"PJ50"
NEEDS_NO_SIZE"TRUE"
CDS_LIB"pure_quanta"
LOCATION"PJ50"
$SEC"1"
CDS_SEC"1";
"1"
$PN"1"75;
"2"
$PN"2"74;
%"Q_RES"
"1","(550,7300)","0","pure_quanta","I55";
;
PART_NUMBER"CS11002FB07"
WATTAGE"1/16W"
MATERIAL"CHIP"
VALUE"100"
PACK_TYPE"0402LF"
TOLERANCE"1%"
LOCATION"PR568"
CDS_LIB"pure_quanta"
$SEC"1"
CDS_SEC"1";
"B"
$PN"2"1;
"A"
$PN"1"75;
%"VCC15"
"1","(1050,7450)","0","logical_power","I56";
;
HDL_POWER"PVCCINFAON_CPU1"
CDS_LIB"logical_power";
"A"1;
%"Q_RES"
"1","(1175,7850)","0","pure_quanta","I57";
;
PART_NUMBER"CS00002JB13"
PACK_TYPE"0402LF"
TOLERANCE"5%"
VALUE"0"
MATERIAL"CHIP"
WATTAGE"1/16W"
LOCATION"R2563"
CDS_LIB"pure_quanta"
LOCATION"R2563"
$SEC"1"
CDS_SEC"1";
"B"
$PN"2"42;
"A"
$PN"1"82;
%"Q_RES"
"1","(1175,8000)","0","pure_quanta","I58";
;
PART_NUMBER"CS00002JB13"
MATERIAL"CHIP"
TOLERANCE"5%"
VALUE"0"
PACK_TYPE"0402LF"
WATTAGE"1/16W"
LOCATION"R4594"
SEC_TYPE"0402LF"
CDS_LIB"pure_quanta"
SEC"1";
"B"
$PN"2"34;
"A"
$PN"1"85;
%"Q_RES"
"1","(1175,8400)","0","pure_quanta","I59";
;
PART_NUMBER"CS00002JB13"
WATTAGE"1/16W"
PACK_TYPE"0402LF"
TOLERANCE"5%"
MATERIAL"CHIP"
VALUE"0"
LOCATION"R2561"
CDS_LIB"pure_quanta"
LOCATION"R2561"
$SEC"1"
CDS_SEC"1";
"B"
$PN"2"36;
"A"
$PN"1"79;
%"Q_RES"
"1","(1175,8550)","0","pure_quanta","I60";
;
PART_NUMBER"CS00002JB13"
MATERIAL"CHIP"
PACK_TYPE"0402LF"
WATTAGE"1/16W"
TOLERANCE"5%"
VALUE"0"
LOCATION"R2560"
CDS_LIB"pure_quanta"
LOCATION"R2560"
$SEC"1"
CDS_SEC"1";
"B"
$PN"2"35;
"A"
$PN"1"81;
%"Q_RES"
"1","(1175,8700)","0","pure_quanta","I61";
;
PART_NUMBER"CS11502FB07"
MATERIAL"CHIP"
VALUE"150"
TOLERANCE"1%"
WATTAGE"1/16W"
PACK_TYPE"0402LF"
LOCATION"R2559"
CDS_LIB"pure_quanta"
LOCATION"R2559"
$SEC"1"
CDS_SEC"1";
"B"
$PN"2"38;
"A"
$PN"1"83;
%"Q_RES"
"1","(1525,7150)","0","pure_quanta","I62";
;
PART_NUMBER"CS00002JB13"
TOLERANCE"5%"
VALUE"0"
PACK_TYPE"0402LF"
WATTAGE"1/16W"
MATERIAL"CHIP"
LOCATION"PR273"
CDS_LIB"pure_quanta"
LOCATION"PR273"
$SEC"1"
CDS_SEC"1";
"B"
$PN"2"43;
"A"
$PN"1"74;
%"Q_CAP"
"2","(2000,8875)","0","pure_quanta","I63";
;
PART_NUMBER"TMP_QCH21006JB10"
TOLERANCE"5%"
PACK_TYPE"0402"
MATERIAL"X7R"
VOLTAGE"50V"
VALUE"1000PF"
LOCATION"C2451"
CDS_LIB"pure_quanta"
LOCATION"C2451"
$SEC"1"
CDS_SEC"1";
"A"
$PN"1"40;
"B"
$PN"2"18;
%"UNIVERSAL_GND"
"1","(2725,8875)","1","logical_power","I64";
;
HDL_POWER"GND"
CDS_LIB"logical_power";
"A"18;
%"UNIVERSAL_GND"
"1","(4375,3550)","0","logical_power","I65";
;
HDL_POWER"GND"
CDS_LIB"logical_power";
"A"19;
%"Q_CAP"
"1","(4375,3775)","0","pure_quanta","I66";
;
PART_NUMBER"TMP_QCH14706KB18"
VALUE"470PF"
VOLTAGE"50V"
TOLERANCE"10%"
MATERIAL"X7R"
PACK_TYPE"0402"
LOCATION"PC475"
CDS_LIB"pure_quanta"
LOCATION"PC475"
$SEC"1"
CDS_SEC"1";
"B"
$PN"2"19;
"A"
$PN"1"52;
%"Q_RES"
"2","(5100,3750)","0","pure_quanta","I67";
;
PART_NUMBER"CS31002FB08"
TOLERANCE"1%"
PACK_TYPE"0402LF"
VALUE"10K"
MATERIAL"EMPTY"
WATTAGE"1/16W"
LOCATION"PR665"
CDS_LIB"pure_quanta"
$SEC"1"
CDS_SEC"1";
"A"
$PN"1"52;
"B"
$PN"2"20;
%"UNIVERSAL_GND"
"1","(5100,3500)","0","logical_power","I68";
;
HDL_POWER"GND"
CDS_LIB"logical_power";
"A"20;
%"Q_CAP"
"2","(4700,4400)","0","pure_quanta","I69";
;
PART_NUMBER"TMP_QCH14706KB18"
VOLTAGE"50V"
MATERIAL"X7R"
TOLERANCE"10%"
VALUE"470PF"
PACK_TYPE"0402"
LOCATION"PC1292"
CDS_LIB"pure_quanta"
$SEC"1"
CDS_SEC"1";
"A"
$PN"1"59;
"B"
$PN"2"21;
%"Q_RES"
"1","(5675,4650)","0","pure_quanta","I70";
;
PART_NUMBER"CS00002JB13"
VALUE"0"
TOLERANCE"5%"
WATTAGE"1/16W"
MATERIAL"CHIP"
PACK_TYPE"0402LF"
LOCATION"R2574"
CDS_LIB"pure_quanta"
$SEC"1"
CDS_SEC"1";
"B"
$PN"2"71;
"A"
$PN"1"67;
%"UNIVERSAL_GND"
"1","(5425,4400)","1","logical_power","I71";
;
HDL_POWER"GND"
CDS_LIB"logical_power";
"A"21;
%"Q_RES"
"2","(6275,4900)","0","pure_quanta","I73";
;
PART_NUMBER"CS21002FB06"
WATTAGE"1/16W"
TOLERANCE"1%"
VALUE"1K"
PACK_TYPE"0402LF"
MATERIAL"CHIP"
LOCATION"R2573"
CDS_LIB"pure_quanta"
LOCATION"R2573"
$SEC"1"
CDS_SEC"1";
"A"
$PN"1"7;
"B"
$PN"2"71;
%"UNIVERSAL_GND"
"1","(6700,3800)","0","logical_power","I74";
;
HDL_POWER"GND"
CDS_LIB"logical_power";
"A"22;
%"Q_RES"
"2","(6700,4050)","0","pure_quanta","I75";
;
PART_NUMBER"CS31002FB08"
WATTAGE"1/16W"
MATERIAL"EMPTY"
TOLERANCE"1%"
VALUE"10K"
PACK_TYPE"0402LF"
LOCATION"PR667"
CDS_LIB"pure_quanta"
$SEC"1"
CDS_SEC"1";
"A"
$PN"1"59;
"B"
$PN"2"22;
%"Q_RES"
"1","(5350,5350)","0","pure_quanta","I78";
;
PART_NUMBER"CS00002JB13"
PACK_TYPE"0402LF"
TOLERANCE"5%"
MATERIAL"CHIP"
WATTAGE"1/16W"
VALUE"0"
LOCATION"PR4246"
CDS_LIB"pure_quanta"
$SEC"1"
CDS_SEC"1";
"B"
$PN"2"23;
"A"
$PN"1"58;
%"Q_RES"
"1","(5350,5800)","0","pure_quanta","I79";
;
PART_NUMBER"CS00002JB13"
VALUE"0"
TOLERANCE"5%"
MATERIAL"CHIP"
LOCATION"PR4245"
PACK_TYPE"0402LF"
WATTAGE"1/16W"
CDS_LIB"pure_quanta"
$SEC"1"
CDS_SEC"1";
"B"
$PN"2"24;
"A"
$PN"1"53;
%"Q_RES"
"1","(5350,6250)","0","pure_quanta","I80";
;
PART_NUMBER"CS00002JB13"
WATTAGE"1/16W"
PACK_TYPE"0402LF"
VALUE"0"
MATERIAL"CHIP"
TOLERANCE"5%"
LOCATION"PR4244"
CDS_LIB"pure_quanta"
$SEC"1"
CDS_SEC"1";
"B"
$PN"2"25;
"A"
$PN"1"55;
%"Q_RES"
"1","(5350,6700)","0","pure_quanta","I81";
;
PART_NUMBER"CS00002JB13"
PACK_TYPE"0402LF"
WATTAGE"1/16W"
TOLERANCE"5%"
VALUE"0"
MATERIAL"CHIP"
LOCATION"PR4243"
CDS_LIB"pure_quanta"
$SEC"1"
CDS_SEC"1";
"B"
$PN"2"26;
"A"
$PN"1"65;
%"UNIVERSAL_GND"
"1","(5975,5275)","0","logical_power","I84";
;
HDL_POWER"GND"
CDS_LIB"logical_power";
"A"23;
%"VCC15"
"1","(6275,5150)","0","logical_power","I85";
;
HDL_POWER"P3V3_AUX"
CDS_LIB"logical_power";
"A"7;
%"UNIVERSAL_GND"
"1","(5975,5725)","0","logical_power","I86";
;
HDL_POWER"GND"
CDS_LIB"logical_power";
"A"24;
%"UNIVERSAL_GND"
"1","(5975,6175)","0","logical_power","I87";
;
HDL_POWER"GND"
CDS_LIB"logical_power";
"A"25;
%"UNIVERSAL_GND"
"1","(5975,6625)","0","logical_power","I88";
;
HDL_POWER"GND"
CDS_LIB"logical_power";
"A"26;
%"Q_RES"
"1","(5350,7150)","0","pure_quanta","I89";
;
PART_NUMBER"CS00002JB13"
WATTAGE"1/16W"
TOLERANCE"5%"
VALUE"0"
MATERIAL"CHIP"
PACK_TYPE"0402LF"
LOCATION"PR4242"
CDS_LIB"pure_quanta"
$SEC"1"
CDS_SEC"1";
"B"
$PN"2"27;
"A"
$PN"1"66;
%"Q_CAP"
"1","(4800,8475)","0","pure_quanta","I92";
;
PART_NUMBER"CH6101MEB03"
VOLTAGE"6.3V"
VALUE"10UF"
TOLERANCE"20%"
MATERIAL"X6S"
PACK_TYPE"C0402"
LOCATION"PC477"
CDS_LIB"pure_quanta"
LOCATION"PC477"
$SEC"1"
CDS_SEC"1";
"B"
$PN"2"28;
"A"
$PN"1"60;
%"Q_CAP"
"1","(4800,8950)","0","pure_quanta","I93";
;
PART_NUMBER"CH4106K1B01"
VALUE"100NF"
MATERIAL"EMPTY"
TOLERANCE"10%"
VOLTAGE"50V"
PACK_TYPE"C0402"
LOCATION"PC476"
CDS_LIB"pure_quanta"
LOCATION"PC476"
$SEC"1"
CDS_SEC"1";
"B"
$PN"2"29;
"A"
$PN"1"69;
%"Q_CAP"
"1","(5200,8475)","0","pure_quanta","I96";
;
PART_NUMBER"CH5103KEB01"
PACK_TYPE"C0402"
VOLTAGE"16V"
TOLERANCE"10%"
MATERIAL"X6S"
VALUE"1UF"
LOCATION"PC1193"
CDS_LIB"pure_quanta"
$SEC"1"
CDS_SEC"1";
"B"
$PN"2"28;
"A"
$PN"1"60;
%"Q_CAP"
"1","(5200,8950)","0","pure_quanta","I97";
;
PART_NUMBER"CH5103KEB01"
VOLTAGE"16V"
TOLERANCE"10%"
MATERIAL"X6S"
VALUE"1UF"
PACK_TYPE"C0402"
LOCATION"PC478"
CDS_LIB"pure_quanta"
LOCATION"PC478"
$SEC"1"
CDS_SEC"1";
"B"
$PN"2"29;
"A"
$PN"1"69;
%"UNIVERSAL_GND"
"1","(5975,7075)","0","logical_power","I98";
;
HDL_POWER"GND"
CDS_LIB"logical_power";
"A"27;
%"UNIVERSAL_GND"
"1","(5650,8275)","3","logical_power","I99";
;
HDL_POWER"GND"
CDS_LIB"logical_power";
"A"28;
END.
